# SCM (Grand Teton) — schematic netlist excerpt (pin names and nets, part order shuffled) for the footprints in the layout excerpt that follows; sources: Cadence DE-HDL packaged netlist, KiCad conversion of 12092022_DA0F0TMDCD0_F0T_Management_Board_D_brd_V3_OCP.brd

R252  Q_RES  2.2K 5% CHIP  pkg 0402LF  page 27 : A = P3V3_AUX ; B = SMB_BMC_MM5_R_SCL
R283  Q_RES  75 1% CHIP  pkg 0402LF  page 49 : A = FM_UARTSW_LSB_N ; B = FM_UARTSW_LSB_R1_N

(kicad_pcb
	(version 20260206)
	(generator "pcbnew")
	(generator_version "10.0")
	(general
		(thickness 1.6)
		(legacy_teardrops no)
	)
	(paper "A4")
	(title_block
		(title "12092022_DA0F0TMDCD0_F0T_Management_Board_D_brd_V3_OCP.brd")
		(comment 1 "Grand Teton / footprints 206-207 of 1440")
	)
	(layers
		(0 "F.Cu" signal "TOP")
		(4 "In1.Cu" signal "GND")
		(6 "In2.Cu" signal "IN1")
		(8 "In3.Cu" signal "GND1")
		(10 "In4.Cu" signal "IN2")
		(12 "In5.Cu" signal "VCC")
		(14 "In6.Cu" signal "VCC1")
		(16 "In7.Cu" signal "IN3")
		(18 "In8.Cu" signal "GND2")
		(20 "In9.Cu" signal "IN4")
		(22 "In10.Cu" signal "GND3")
		(2 "B.Cu" signal "BOTTOM")
		(9 "F.Adhes" user "F.Adhesive")
		(11 "B.Adhes" user "B.Adhesive")
		(13 "F.Paste" user "Package Geometry/Pastemask Top")
		(15 "B.Paste" user "Package Geometry/Pastemask Bottom")
		(5 "F.SilkS" user "Ref Des/Silkscreen Top")
		(7 "B.SilkS" user "Ref Des/Silkscreen Bottom")
		(1 "F.Mask" user "Board Geometry/Soldermask Top")
		(3 "B.Mask" user "Board Geometry/Soldermask Bottom")
		(17 "Dwgs.User" user "User.Drawings")
		(19 "Cmts.User" user "User.Comments")
		(21 "Eco1.User" user "User.Eco1")
		(23 "Eco2.User" user "User.Eco2")
		(25 "Edge.Cuts" user "Board Geometry/Outline")
		(27 "Margin" user)
		(31 "F.CrtYd" user "Package Geometry/Place Bound Top")
		(29 "B.CrtYd" user "Package Geometry/Place Bound Bottom")
		(35 "F.Fab" user "Ref Des/Assembly Top")
		(33 "B.Fab" user "Ref Des/Assembly Bottom")
	)
	(footprint ""
		(layer "F.Cu")
		(at 60.549028 -30.867604 90)
		(property "Reference" "R252"
			(at 0 0 90)
			(layer "F.SilkS")
			(hide yes)
			(effects
				(font
					(size 1.27 1.27)
				)
			)
		)
		(property "Value" ""
			(at 0 0 90)
			(layer "F.Fab")
			(effects
				(font
					(size 1.27 1.27)
				)
			)
		)
		(duplicate_pad_numbers_are_jumpers no)
		(fp_line
			(start 0.7874 -0.4064)
			(end 0.7874 0.4064)
			(stroke
				(width 0.1524)
				(type default)
			)
			(layer "F.SilkS")
		)
		(fp_line
			(start -0.7874 -0.4064)
			(end 0.7874 -0.4064)
			(stroke
				(width 0.1524)
				(type default)
			)
			(layer "F.SilkS")
		)
		(fp_line
			(start 0.7874 0.4064)
			(end -0.7874 0.4064)
			(stroke
				(width 0.1524)
				(type default)
			)
			(layer "F.SilkS")
		)
		(fp_line
			(start -0.7874 0.4064)
			(end -0.7874 -0.4064)
			(stroke
				(width 0.1524)
				(type default)
			)
			(layer "F.SilkS")
		)
		(fp_line
			(start -0.12065 -0.305054)
			(end -0.12065 -0.2794)
			(stroke
				(width 0.1)
				(type default)
			)
			(layer "F.Fab")
		)
		(fp_line
			(start -0.67945 -0.305054)
			(end -0.12065 -0.305054)
			(stroke
				(width 0.1)
				(type default)
			)
			(layer "F.Fab")
		)
		(fp_line
			(start 0.67945 -0.3048)
			(end 0.67945 0.3048)
			(stroke
				(width 0.1)
				(type default)
			)
			(layer "F.Fab")
		)
		(fp_line
			(start 0.12065 -0.3048)
			(end 0.67945 -0.3048)
			(stroke
				(width 0.1)
				(type default)
			)
			(layer "F.Fab")
		)
		(fp_line
			(start 0.12065 -0.2794)
			(end 0.12065 -0.3048)
			(stroke
				(width 0.1)
				(type default)
			)
			(layer "F.Fab")
		)
		(fp_line
			(start -0.12065 -0.2794)
			(end 0.12065 -0.2794)
			(stroke
				(width 0.1)
				(type default)
			)
			(layer "F.Fab")
		)
		(fp_line
			(start 0.120396 0.2794)
			(end -0.12065 0.2794)
			(stroke
				(width 0.1)
				(type default)
			)
			(layer "F.Fab")
		)
		(fp_line
			(start -0.12065 0.2794)
			(end -0.12065 0.3048)
			(stroke
				(width 0.1)
				(type default)
			)
			(layer "F.Fab")
		)
		(fp_line
			(start 0.67945 0.3048)
			(end 0.120396 0.3048)
			(stroke
				(width 0.1)
				(type default)
			)
			(layer "F.Fab")
		)
		(fp_line
			(start 0.120396 0.3048)
			(end 0.120396 0.2794)
			(stroke
				(width 0.1)
				(type default)
			)
			(layer "F.Fab")
		)
		(fp_line
			(start -0.12065 0.3048)
			(end -0.67945 0.3048)
			(stroke
				(width 0.1)
				(type default)
			)
			(layer "F.Fab")
		)
		(fp_line
			(start -0.67945 0.3048)
			(end -0.67945 -0.305054)
			(stroke
				(width 0.1)
				(type default)
			)
			(layer "F.Fab")
		)
		(pad "1" smd circle
			(at -0.40005 0 90)
			(size 0 0)
			(layers "F.Cu" "F.Mask" "F.Paste")
			(net "P3V3_AUX")
		)
		(pad "2" smd circle
			(at 0.40005 0 90)
			(size 0 0)
			(layers "F.Cu" "F.Mask" "F.Paste")
			(net "SMB_BMC_MM5_R_SCL")
		)
	)
	(footprint ""
		(layer "F.Cu")
		(at 75.184 -20.193 180)
		(property "Reference" "R283"
			(at 0 0 180)
			(layer "F.SilkS")
			(hide yes)
			(effects
				(font
					(size 1.27 1.27)
				)
			)
		)
		(property "Value" ""
			(at 0 0 180)
			(layer "F.Fab")
			(effects
				(font
					(size 1.27 1.27)
				)
			)
		)
		(duplicate_pad_numbers_are_jumpers no)
		(fp_line
			(start 0.7874 0.4064)
			(end -0.7874 0.4064)
			(stroke
				(width 0.1524)
				(type default)
			)
			(layer "F.SilkS")
		)
		(fp_line
			(start 0.7874 -0.4064)
			(end 0.7874 0.4064)
			(stroke
				(width 0.1524)
				(type default)
			)
			(layer "F.SilkS")
		)
		(fp_line
			(start -0.7874 0.4064)
			(end -0.7874 -0.4064)
			(stroke
				(width 0.1524)
				(type default)
			)
			(layer "F.SilkS")
		)
		(fp_line
			(start -0.7874 -0.4064)
			(end 0.7874 -0.4064)
			(stroke
				(width 0.1524)
				(type default)
			)
			(layer "F.SilkS")
		)
		(fp_line
			(start 0.67945 0.3048)
			(end 0.120396 0.3048)
			(stroke
				(width 0.1)
				(type default)
			)
			(layer "F.Fab")
		)
		(fp_line
			(start 0.67945 -0.3048)
			(end 0.67945 0.3048)
			(stroke
				(width 0.1)
				(type default)
			)
			(layer "F.Fab")
		)
		(fp_line
			(start 0.12065 -0.2794)
			(end 0.12065 -0.3048)
			(stroke
				(width 0.1)
				(type default)
			)
			(layer "F.Fab")
		)
		(fp_line
			(start 0.12065 -0.3048)
			(end 0.67945 -0.3048)
			(stroke
				(width 0.1)
				(type default)
			)
			(layer "F.Fab")
		)
		(fp_line
			(start 0.120396 0.3048)
			(end 0.120396 0.2794)
			(stroke
				(width 0.1)
				(type default)
			)
			(layer "F.Fab")
		)
		(fp_line
			(start 0.120396 0.2794)
			(end -0.12065 0.2794)
			(stroke
				(width 0.1)
				(type default)
			)
			(layer "F.Fab")
		)
		(fp_line
			(start -0.12065 0.3048)
			(end -0.67945 0.3048)
			(stroke
				(width 0.1)
				(type default)
			)
			(layer "F.Fab")
		)
		(fp_line
			(start -0.12065 0.2794)
			(end -0.12065 0.3048)
			(stroke
				(width 0.1)
				(type default)
			)
			(layer "F.Fab")
		)
		(fp_line
			(start -0.12065 -0.2794)
			(end 0.12065 -0.2794)
			(stroke
				(width 0.1)
				(type default)
			)
			(layer "F.Fab")
		)
		(fp_line
			(start -0.12065 -0.305054)
			(end -0.12065 -0.2794)
			(stroke
				(width 0.1)
				(type default)
			)
			(layer "F.Fab")
		)
		(fp_line
			(start -0.67945 0.3048)
			(end -0.67945 -0.305054)
			(stroke
				(width 0.1)
				(type default)
			)
			(layer "F.Fab")
		)
		(fp_line
			(start -0.67945 -0.305054)
			(end -0.12065 -0.305054)
			(stroke
				(width 0.1)
				(type default)
			)
			(layer "F.Fab")
		)
		(pad "1" smd circle
			(at -0.40005 0 180)
			(size 0 0)
			(layers "F.Cu" "F.Mask" "F.Paste")
			(net "FM_UARTSW_LSB_N")
		)
		(pad "2" smd circle
			(at 0.40005 0 180)
			(size 0 0)
			(layers "F.Cu" "F.Mask" "F.Paste")
			(net "FM_UARTSW_LSB_R1_N")
		)
	)
)
